# S9S_MB_2U (Grand Teton) — schematic netlist excerpt (pin names and nets, part order shuffled) for the footprints in the layout excerpt that follows; sources: Cadence DE-HDL packaged netlist, KiCad conversion of 03242023_DA0F0TMBIJ0_F0T_Motherboard_J_brd_V01_OCP.brd

R2491  Q_RES  1K 1% CHIP  pkg 0402LF  page 115 : A = PWRGD_FAIL_CPU0_CD ; B = PWRGD_FAIL_CPU0_CD_R1
PC377  Q_CAP  22UF 16V 20% X6S  pkg C0805  page 297 : A = SW_P12V_PVCCINFAON_CPU1_FLT ; B = GND
PC450_P1_1  Q_CAP  22UF 16V 20% X6S  pkg C0805  page 293 : A = SW_P12V_PVCCINFAON_CPU1_FLT ; B = GND

(kicad_pcb
	(version 20260206)
	(generator "pcbnew")
	(generator_version "10.0")
	(general
		(thickness 1.6)
		(legacy_teardrops no)
	)
	(paper "A4")
	(title_block
		(title "03242023_DA0F0TMBIJ0_F0T_Motherboard_J_brd_V01_OCP.brd")
		(comment 1 "Grand Teton / footprints 4346-4348 of 6105")
	)
	(layers
		(0 "F.Cu" signal "TOP")
		(4 "In1.Cu" signal "GND")
		(6 "In2.Cu" signal "IN1")
		(8 "In3.Cu" signal "GND1")
		(10 "In4.Cu" signal "IN2")
		(12 "In5.Cu" signal "GND2")
		(14 "In6.Cu" signal "IN3")
		(16 "In7.Cu" signal "GND3")
		(18 "In8.Cu" signal "VCC")
		(20 "In9.Cu" signal "VCC1")
		(22 "In10.Cu" signal "GND4")
		(24 "In11.Cu" signal "IN4")
		(26 "In12.Cu" signal "GND5")
		(28 "In13.Cu" signal "IN5")
		(30 "In14.Cu" signal "GND6")
		(32 "In15.Cu" signal "IN6")
		(34 "In16.Cu" signal "GND7")
		(2 "B.Cu" signal "BOTTOM")
		(9 "F.Adhes" user "F.Adhesive")
		(11 "B.Adhes" user "B.Adhesive")
		(13 "F.Paste" user "Package Geometry/Pastemask Top")
		(15 "B.Paste" user "Package Geometry/Pastemask Bottom")
		(5 "F.SilkS" user "Ref Des/Silkscreen Top")
		(7 "B.SilkS" user "Ref Des/Silkscreen Bottom")
		(1 "F.Mask" user "Board Geometry/Soldermask Top")
		(3 "B.Mask" user "Board Geometry/Soldermask Bottom")
		(17 "Dwgs.User" user "User.Drawings")
		(19 "Cmts.User" user "User.Comments")
		(21 "Eco1.User" user "User.Eco1")
		(23 "Eco2.User" user "User.Eco2")
		(25 "Edge.Cuts" user "Board Geometry/Outline")
		(27 "Margin" user)
		(31 "F.CrtYd" user "Package Geometry/Place Bound Top")
		(29 "B.CrtYd" user "Package Geometry/Place Bound Bottom")
		(35 "F.Fab" user "Ref Des/Assembly Top")
		(33 "B.Fab" user "Ref Des/Assembly Bottom")
	)
	(footprint ""
		(layer "B.Cu")
		(at 284.075378 -318.376046 180)
		(property "Reference" "R2491"
			(at 0 0 0)
			(layer "B.SilkS")
			(hide yes)
			(effects
				(font
					(size 1.27 1.27)
				)
				(justify mirror)
			)
		)
		(property "Value" ""
			(at 0 0 0)
			(layer "B.Fab")
			(effects
				(font
					(size 1.27 1.27)
				)
				(justify mirror)
			)
		)
		(duplicate_pad_numbers_are_jumpers no)
		(fp_line
			(start 0.7874 0.4064)
			(end 0.7874 -0.4064)
			(stroke
				(width 0.1524)
				(type default)
			)
			(layer "B.SilkS")
		)
		(fp_line
			(start 0.7874 -0.4064)
			(end -0.7874 -0.4064)
			(stroke
				(width 0.1524)
				(type default)
			)
			(layer "B.SilkS")
		)
		(fp_line
			(start -0.7874 0.4064)
			(end 0.7874 0.4064)
			(stroke
				(width 0.1524)
				(type default)
			)
			(layer "B.SilkS")
		)
		(fp_line
			(start -0.7874 -0.4064)
			(end -0.7874 0.4064)
			(stroke
				(width 0.1524)
				(type default)
			)
			(layer "B.SilkS")
		)
		(fp_line
			(start 0.67945 0.3048)
			(end 0.67945 -0.305054)
			(stroke
				(width 0.1)
				(type default)
			)
			(layer "B.Fab")
		)
		(fp_line
			(start 0.67945 -0.305054)
			(end 0.12065 -0.305054)
			(stroke
				(width 0.1)
				(type default)
			)
			(layer "B.Fab")
		)
		(fp_line
			(start 0.12065 0.3048)
			(end 0.67945 0.3048)
			(stroke
				(width 0.1)
				(type default)
			)
			(layer "B.Fab")
		)
		(fp_line
			(start 0.12065 0.2794)
			(end 0.12065 0.3048)
			(stroke
				(width 0.1)
				(type default)
			)
			(layer "B.Fab")
		)
		(fp_line
			(start 0.12065 -0.2794)
			(end -0.12065 -0.2794)
			(stroke
				(width 0.1)
				(type default)
			)
			(layer "B.Fab")
		)
		(fp_line
			(start 0.12065 -0.305054)
			(end 0.12065 -0.2794)
			(stroke
				(width 0.1)
				(type default)
			)
			(layer "B.Fab")
		)
		(fp_line
			(start -0.120396 0.3048)
			(end -0.120396 0.2794)
			(stroke
				(width 0.1)
				(type default)
			)
			(layer "B.Fab")
		)
		(fp_line
			(start -0.120396 0.2794)
			(end 0.12065 0.2794)
			(stroke
				(width 0.1)
				(type default)
			)
			(layer "B.Fab")
		)
		(fp_line
			(start -0.12065 -0.2794)
			(end -0.12065 -0.3048)
			(stroke
				(width 0.1)
				(type default)
			)
			(layer "B.Fab")
		)
		(fp_line
			(start -0.12065 -0.3048)
			(end -0.67945 -0.3048)
			(stroke
				(width 0.1)
				(type default)
			)
			(layer "B.Fab")
		)
		(fp_line
			(start -0.67945 0.3048)
			(end -0.120396 0.3048)
			(stroke
				(width 0.1)
				(type default)
			)
			(layer "B.Fab")
		)
		(fp_line
			(start -0.67945 -0.3048)
			(end -0.67945 0.3048)
			(stroke
				(width 0.1)
				(type default)
			)
			(layer "B.Fab")
		)
		(pad "1" smd circle
			(at 0.40005 0)
			(size 0 0)
			(layers "B.Cu" "B.Mask" "B.Paste")
			(net "PWRGD_FAIL_CPU0_CD")
		)
		(pad "2" smd circle
			(at -0.40005 0)
			(size 0 0)
			(layers "B.Cu" "B.Mask" "B.Paste")
			(net "PWRGD_FAIL_CPU0_CD_R1")
		)
	)
	(footprint ""
		(layer "B.Cu")
		(at 54.880002 -157.599634 180)
		(property "Reference" "PC450_P1_1"
			(at 0 0 0)
			(layer "B.SilkS")
			(hide yes)
			(effects
				(font
					(size 1.27 1.27)
				)
				(justify mirror)
			)
		)
		(property "Value" ""
			(at 0 0 0)
			(layer "B.Fab")
			(effects
				(font
					(size 1.27 1.27)
				)
				(justify mirror)
			)
		)
		(duplicate_pad_numbers_are_jumpers no)
		(fp_line
			(start 1.524 0.762)
			(end 1.524 -0.762)
			(stroke
				(width 0.1524)
				(type default)
			)
			(layer "B.SilkS")
		)
		(fp_line
			(start 1.524 -0.762)
			(end -1.524 -0.762)
			(stroke
				(width 0.1524)
				(type default)
			)
			(layer "B.SilkS")
		)
		(fp_line
			(start -1.524 0.762)
			(end 1.524 0.762)
			(stroke
				(width 0.1524)
				(type default)
			)
			(layer "B.SilkS")
		)
		(fp_line
			(start -1.524 -0.762)
			(end -1.524 0.762)
			(stroke
				(width 0.1524)
				(type default)
			)
			(layer "B.SilkS")
		)
		(fp_line
			(start 1.1049 0.724916)
			(end -1.1049 0.724916)
			(stroke
				(width 0.1)
				(type default)
			)
			(layer "B.Fab")
		)
		(fp_line
			(start 1.1049 -0.724916)
			(end 1.1049 0.724916)
			(stroke
				(width 0.1)
				(type default)
			)
			(layer "B.Fab")
		)
		(fp_line
			(start -1.1049 0.724916)
			(end -1.1049 -0.724916)
			(stroke
				(width 0.1)
				(type default)
			)
			(layer "B.Fab")
		)
		(fp_line
			(start -1.1049 -0.724916)
			(end 1.1049 -0.724916)
			(stroke
				(width 0.1)
				(type default)
			)
			(layer "B.Fab")
		)
		(pad "1" smd rect
			(at 0.889 0 180)
			(size 1.016 1.27)
			(layers "B.Cu" "B.Mask" "B.Paste")
			(net "SW_P12V_PVCCINFAON_CPU1_FLT")
		)
		(pad "2" smd rect
			(at -0.889 0 180)
			(size 1.016 1.27)
			(layers "B.Cu" "B.Mask" "B.Paste")
			(net "GND")
		)
	)
	(footprint ""
		(layer "B.Cu")
		(at 54.880002 -166.235634 180)
		(property "Reference" "PC377"
			(at 0 0 0)
			(layer "B.SilkS")
			(hide yes)
			(effects
				(font
					(size 1.27 1.27)
				)
				(justify mirror)
			)
		)
		(property "Value" ""
			(at 0 0 0)
			(layer "B.Fab")
			(effects
				(font
					(size 1.27 1.27)
				)
				(justify mirror)
			)
		)
		(duplicate_pad_numbers_are_jumpers no)
		(fp_line
			(start 1.524 0.762)
			(end 1.524 -0.762)
			(stroke
				(width 0.1524)
				(type default)
			)
			(layer "B.SilkS")
		)
		(fp_line
			(start 1.524 -0.762)
			(end -1.524 -0.762)
			(stroke
				(width 0.1524)
				(type default)
			)
			(layer "B.SilkS")
		)
		(fp_line
			(start -1.524 0.762)
			(end 1.524 0.762)
			(stroke
				(width 0.1524)
				(type default)
			)
			(layer "B.SilkS")
		)
		(fp_line
			(start -1.524 -0.762)
			(end -1.524 0.762)
			(stroke
				(width 0.1524)
				(type default)
			)
			(layer "B.SilkS")
		)
		(fp_line
			(start 1.1049 0.724916)
			(end -1.1049 0.724916)
			(stroke
				(width 0.1)
				(type default)
			)
			(layer "B.Fab")
		)
		(fp_line
			(start 1.1049 -0.724916)
			(end 1.1049 0.724916)
			(stroke
				(width 0.1)
				(type default)
			)
			(layer "B.Fab")
		)
		(fp_line
			(start -1.1049 0.724916)
			(end -1.1049 -0.724916)
			(stroke
				(width 0.1)
				(type default)
			)
			(layer "B.Fab")
		)
		(fp_line
			(start -1.1049 -0.724916)
			(end 1.1049 -0.724916)
			(stroke
				(width 0.1)
				(type default)
			)
			(layer "B.Fab")
		)
		(pad "1" smd rect
			(at 0.889 0 180)
			(size 1.016 1.27)
			(layers "B.Cu" "B.Mask" "B.Paste")
			(net "SW_P12V_PVCCINFAON_CPU1_FLT")
		)
		(pad "2" smd rect
			(at -0.889 0 180)
			(size 1.016 1.27)
			(layers "B.Cu" "B.Mask" "B.Paste")
			(net "GND")
		)
	)
)
